(kicad_pcb
	(version 20260206)
	(generator "pcbnew")
	(generator_version "10.0")
	(general
		(thickness 1.6)
		(legacy_teardrops no)
	)
	(paper "A4")
	(title_block
		(title "Bryce Canyon_SCC_16316-1_OCP.brd")
		(comment 1 "Bryce Canyon / footprints 609-616 of 1561")
	)
	(layers
		(0 "F.Cu" signal "TOP")
		(4 "In1.Cu" signal "L2GND")
		(6 "In2.Cu" signal "L3")
		(8 "In3.Cu" signal "L4VCC")
		(10 "In4.Cu" signal "L5VCC")
		(12 "In5.Cu" signal "L6")
		(14 "In6.Cu" signal "L7GND")
		(2 "B.Cu" signal "BOTTOM")
		(9 "F.Adhes" user "F.Adhesive")
		(11 "B.Adhes" user "B.Adhesive")
		(13 "F.Paste" user "Package Geometry/Pastemask Top")
		(15 "B.Paste" user "Package Geometry/Pastemask Bottom")
		(5 "F.SilkS" user "Ref Des/Silkscreen Top")
		(7 "B.SilkS" user "Ref Des/Silkscreen Bottom")
		(1 "F.Mask" user "Board Geometry/Soldermask Top")
		(3 "B.Mask" user "Board Geometry/Soldermask Bottom")
		(17 "Dwgs.User" user "User.Drawings")
		(19 "Cmts.User" user "User.Comments")
		(21 "Eco1.User" user "User.Eco1")
		(23 "Eco2.User" user "User.Eco2")
		(25 "Edge.Cuts" user "Board Geometry/Outline")
		(27 "Margin" user)
		(31 "F.CrtYd" user "Package Geometry/Place Bound Top")
		(29 "B.CrtYd" user "Package Geometry/Place Bound Bottom")
		(35 "F.Fab" user "Ref Des/Assembly Top")
		(33 "B.Fab" user "Ref Des/Assembly Bottom")
	)
	(footprint ""
		(layer "F.Cu")
		(at 7.4422 -42.037 90)
		(property "Reference" "R525"
			(at 0 0 90)
			(layer "F.SilkS")
			(hide yes)
			(effects
				(font
					(size 1.27 1.27)
				)
			)
		)
		(property "Value" "0R2J-2-GP"
			(at 0.064008 -3.993896 90)
			(unlocked yes)
			(layer "F.Fab")
			(hide yes)
			(effects
				(font
					(size 1.016 1.016)
					(thickness 0.1524)
				)
			)
		)
		(property "Device Type" "R402H16"
			(at 0.064008 -5.517896 90)
			(unlocked yes)
			(layer "F.Fab")
			(hide yes)
			(effects
				(font
					(size 1.016 1.016)
					(thickness 0.1524)
				)
			)
		)
		(duplicate_pad_numbers_are_jumpers no)
		(fp_line
			(start 0.508 -0.9398)
			(end -0.508 -0.9398)
			(stroke
				(width 0.1524)
				(type default)
			)
			(layer "F.SilkS")
		)
		(fp_line
			(start -0.508 -0.9398)
			(end -0.508 0.9398)
			(stroke
				(width 0.1524)
				(type default)
			)
			(layer "F.SilkS")
		)
		(fp_rect
			(start -0.508 0.9398)
			(end 0.508 -0.9398)
			(stroke
				(width 0)
				(type default)
			)
			(fill no)
			(layer "F.CrtYd")
		)
		(fp_rect
			(start -0.508 0.9398)
			(end 0.508 -0.9398)
			(stroke
				(width 0)
				(type default)
			)
			(fill no)
			(layer "F.Fab")
		)
		(pad "1" smd custom
			(at 0 -0.4445 90)
			(size 0.1397 0.1397)
			(layers "F.Cu" "F.Mask" "F.Paste")
			(net "MB0_12V_CTRL_GATE1_R")
			(options
				(clearance outline)
				(anchor circle)
			)
			(primitives
				(gr_poly
					(pts
						(arc
							(start -0.1778 -0.2794)
							(mid -0.249642 -0.249642)
							(end -0.2794 -0.1778)
						)
						(arc
							(start -0.2794 0.1778)
							(mid -0.249642 0.249642)
							(end -0.1778 0.2794)
						)
						(arc
							(start 0.1778 0.2794)
							(mid 0.249642 0.249642)
							(end 0.2794 0.1778)
						)
						(arc
							(start 0.2794 -0.1778)
							(mid 0.249642 -0.249642)
							(end 0.1778 -0.2794)
						)
					)
					(width 0)
					(fill yes)
				)
			)
		)
		(pad "2" smd custom
			(at 0 0.4445 90)
			(size 0.1397 0.1397)
			(layers "F.Cu" "F.Mask" "F.Paste")
			(net "MB0_CM_GATE_R")
			(options
				(clearance outline)
				(anchor circle)
			)
			(primitives
				(gr_poly
					(pts
						(arc
							(start -0.1778 -0.2794)
							(mid -0.249642 -0.249642)
							(end -0.2794 -0.1778)
						)
						(arc
							(start -0.2794 0.1778)
							(mid -0.249642 0.249642)
							(end -0.1778 0.2794)
						)
						(arc
							(start 0.1778 0.2794)
							(mid 0.249642 0.249642)
							(end 0.2794 0.1778)
						)
						(arc
							(start 0.2794 -0.1778)
							(mid 0.249642 -0.249642)
							(end 0.1778 -0.2794)
						)
					)
					(width 0)
					(fill yes)
				)
			)
		)
	)
	(footprint ""
		(layer "F.Cu")
		(at 187.833 -56.5658 180)
		(property "Reference" "R224"
			(at 0 0 180)
			(layer "F.SilkS")
			(hide yes)
			(effects
				(font
					(size 1.27 1.27)
				)
			)
		)
		(property "Value" "10KR2F-2-GP"
			(at 0.064008 -3.993896 180)
			(unlocked yes)
			(layer "F.Fab")
			(hide yes)
			(effects
				(font
					(size 1.016 1.016)
					(thickness 0.1524)
				)
			)
		)
		(property "Device Type" "R402H16"
			(at 0.064008 -5.517896 180)
			(unlocked yes)
			(layer "F.Fab")
			(hide yes)
			(effects
				(font
					(size 1.016 1.016)
					(thickness 0.1524)
				)
			)
		)
		(duplicate_pad_numbers_are_jumpers no)
		(fp_line
			(start 0.508 -0.9398)
			(end -0.508 -0.9398)
			(stroke
				(width 0.1524)
				(type default)
			)
			(layer "F.SilkS")
		)
		(fp_line
			(start -0.508 -0.9398)
			(end -0.508 0.9398)
			(stroke
				(width 0.1524)
				(type default)
			)
			(layer "F.SilkS")
		)
		(fp_rect
			(start -0.508 0.9398)
			(end 0.508 -0.9398)
			(stroke
				(width 0)
				(type default)
			)
			(fill no)
			(layer "F.CrtYd")
		)
		(fp_rect
			(start -0.508 0.9398)
			(end 0.508 -0.9398)
			(stroke
				(width 0)
				(type default)
			)
			(fill no)
			(layer "F.Fab")
		)
		(pad "1" smd custom
			(at 0 -0.4445 180)
			(size 0.1397 0.1397)
			(layers "F.Cu" "F.Mask" "F.Paste")
			(net "XM_ADDR_4")
			(options
				(clearance outline)
				(anchor circle)
			)
			(primitives
				(gr_poly
					(pts
						(arc
							(start -0.1778 -0.2794)
							(mid -0.249642 -0.249642)
							(end -0.2794 -0.1778)
						)
						(arc
							(start -0.2794 0.1778)
							(mid -0.249642 0.249642)
							(end -0.1778 0.2794)
						)
						(arc
							(start 0.1778 0.2794)
							(mid 0.249642 0.249642)
							(end 0.2794 0.1778)
						)
						(arc
							(start 0.2794 -0.1778)
							(mid 0.249642 -0.249642)
							(end 0.1778 -0.2794)
						)
					)
					(width 0)
					(fill yes)
				)
			)
		)
		(pad "2" smd custom
			(at 0 0.4445 180)
			(size 0.1397 0.1397)
			(layers "F.Cu" "F.Mask" "F.Paste")
			(net "GND")
			(options
				(clearance outline)
				(anchor circle)
			)
			(primitives
				(gr_poly
					(pts
						(arc
							(start -0.1778 -0.2794)
							(mid -0.249642 -0.249642)
							(end -0.2794 -0.1778)
						)
						(arc
							(start -0.2794 0.1778)
							(mid -0.249642 0.249642)
							(end -0.1778 0.2794)
						)
						(arc
							(start 0.1778 0.2794)
							(mid 0.249642 0.249642)
							(end 0.2794 0.1778)
						)
						(arc
							(start 0.2794 -0.1778)
							(mid 0.249642 -0.249642)
							(end 0.1778 -0.2794)
						)
					)
					(width 0)
					(fill yes)
				)
			)
		)
	)
	(footprint ""
		(layer "F.Cu")
		(at 122.536458 -90.595196 180)
		(property "Reference" "R128"
			(at 0 0 180)
			(layer "F.SilkS")
			(hide yes)
			(effects
				(font
					(size 1.27 1.27)
				)
			)
		)
		(property "Value" "4K7R2F-GP"
			(at 0.064008 -3.993896 180)
			(unlocked yes)
			(layer "F.Fab")
			(hide yes)
			(effects
				(font
					(size 1.016 1.016)
					(thickness 0.1524)
				)
			)
		)
		(property "Device Type" "R402H16"
			(at 0.064008 -5.517896 180)
			(unlocked yes)
			(layer "F.Fab")
			(hide yes)
			(effects
				(font
					(size 1.016 1.016)
					(thickness 0.1524)
				)
			)
		)
		(duplicate_pad_numbers_are_jumpers no)
		(fp_line
			(start 0.508 -0.9398)
			(end -0.508 -0.9398)
			(stroke
				(width 0.1524)
				(type default)
			)
			(layer "F.SilkS")
		)
		(fp_line
			(start -0.508 -0.9398)
			(end -0.508 0.9398)
			(stroke
				(width 0.1524)
				(type default)
			)
			(layer "F.SilkS")
		)
		(fp_rect
			(start -0.508 0.9398)
			(end 0.508 -0.9398)
			(stroke
				(width 0)
				(type default)
			)
			(fill no)
			(layer "F.CrtYd")
		)
		(fp_rect
			(start -0.508 0.9398)
			(end 0.508 -0.9398)
			(stroke
				(width 0)
				(type default)
			)
			(fill no)
			(layer "F.Fab")
		)
		(pad "1" smd custom
			(at 0 -0.4445 180)
			(size 0.1397 0.1397)
			(layers "F.Cu" "F.Mask" "F.Paste")
			(net "USB_NXT")
			(options
				(clearance outline)
				(anchor circle)
			)
			(primitives
				(gr_poly
					(pts
						(arc
							(start -0.1778 -0.2794)
							(mid -0.249642 -0.249642)
							(end -0.2794 -0.1778)
						)
						(arc
							(start -0.2794 0.1778)
							(mid -0.249642 0.249642)
							(end -0.1778 0.2794)
						)
						(arc
							(start 0.1778 0.2794)
							(mid 0.249642 0.249642)
							(end 0.2794 0.1778)
						)
						(arc
							(start 0.2794 -0.1778)
							(mid 0.249642 -0.249642)
							(end 0.1778 -0.2794)
						)
					)
					(width 0)
					(fill yes)
				)
			)
		)
		(pad "2" smd custom
			(at 0 0.4445 180)
			(size 0.1397 0.1397)
			(layers "F.Cu" "F.Mask" "F.Paste")
			(net "GND")
			(options
				(clearance outline)
				(anchor circle)
			)
			(primitives
				(gr_poly
					(pts
						(arc
							(start -0.1778 -0.2794)
							(mid -0.249642 -0.249642)
							(end -0.2794 -0.1778)
						)
						(arc
							(start -0.2794 0.1778)
							(mid -0.249642 0.249642)
							(end -0.1778 0.2794)
						)
						(arc
							(start 0.1778 0.2794)
							(mid 0.249642 0.249642)
							(end 0.2794 0.1778)
						)
						(arc
							(start 0.2794 -0.1778)
							(mid 0.249642 -0.249642)
							(end 0.1778 -0.2794)
						)
					)
					(width 0)
					(fill yes)
				)
			)
		)
	)
	(footprint ""
		(layer "F.Cu")
		(at 70.485 -41.402 90)
		(property "Reference" "R165"
			(at 0 0 90)
			(layer "F.SilkS")
			(hide yes)
			(effects
				(font
					(size 1.27 1.27)
				)
			)
		)
		(property "Value" "D51R3F-2-GP"
			(at -0.0254 -2.5146 90)
			(unlocked yes)
			(layer "F.Fab")
			(hide yes)
			(effects
				(font
					(size 1.016 1.016)
					(thickness 0.1524)
				)
			)
		)
		(property "Device Type" "R603H22"
			(at -0.0254 -4.0386 90)
			(unlocked yes)
			(layer "F.Fab")
			(hide yes)
			(effects
				(font
					(size 1.016 1.016)
					(thickness 0.1524)
				)
			)
		)
		(duplicate_pad_numbers_are_jumpers no)
		(fp_line
			(start 0.2032 0)
			(end 0.4826 0)
			(stroke
				(width 0.2032)
				(type default)
			)
			(layer "F.SilkS")
		)
		(fp_line
			(start -0.4826 0)
			(end -0.2032 0)
			(stroke
				(width 0.2032)
				(type default)
			)
			(layer "F.SilkS")
		)
		(fp_rect
			(start -0.5842 1.3335)
			(end 0.5842 -1.3335)
			(stroke
				(width 0)
				(type default)
			)
			(fill no)
			(layer "F.CrtYd")
		)
		(fp_rect
			(start -0.5842 1.3335)
			(end 0.5842 -1.3335)
			(stroke
				(width 0)
				(type default)
			)
			(fill no)
			(layer "F.Fab")
		)
		(pad "1" smd custom
			(at 0 -0.762 90)
			(size 0.2159 0.2159)
			(layers "F.Cu" "F.Mask" "F.Paste")
			(net "P0V9")
			(options
				(clearance outline)
				(anchor circle)
			)
			(primitives
				(gr_poly
					(pts
						(arc
							(start -0.3302 -0.4318)
							(mid -0.402042 -0.402042)
							(end -0.4318 -0.3302)
						)
						(arc
							(start -0.4318 0.3302)
							(mid -0.402042 0.402042)
							(end -0.3302 0.4318)
						)
						(arc
							(start 0.3302 0.4318)
							(mid 0.402042 0.402042)
							(end 0.4318 0.3302)
						)
						(arc
							(start 0.4318 -0.3302)
							(mid 0.402042 -0.402042)
							(end 0.3302 -0.4318)
						)
					)
					(width 0)
					(fill yes)
				)
			)
		)
		(pad "2" smd custom
			(at 0 0.762 90)
			(size 0.2159 0.2159)
			(layers "F.Cu" "F.Mask" "F.Paste")
			(net "GB_VDDA")
			(options
				(clearance outline)
				(anchor circle)
			)
			(primitives
				(gr_poly
					(pts
						(arc
							(start -0.3302 -0.4318)
							(mid -0.402042 -0.402042)
							(end -0.4318 -0.3302)
						)
						(arc
							(start -0.4318 0.3302)
							(mid -0.402042 0.402042)
							(end -0.3302 0.4318)
						)
						(arc
							(start 0.3302 0.4318)
							(mid 0.402042 0.402042)
							(end 0.4318 0.3302)
						)
						(arc
							(start 0.4318 -0.3302)
							(mid 0.402042 -0.402042)
							(end 0.3302 -0.4318)
						)
					)
					(width 0)
					(fill yes)
				)
			)
		)
	)
	(footprint ""
		(layer "F.Cu")
		(at 56.896 -24.13 90)
		(property "Reference" "C730"
			(at 0 0 90)
			(layer "F.SilkS")
			(hide yes)
			(effects
				(font
					(size 1.27 1.27)
				)
			)
		)
		(property "Value" "SCD1U16V2KX-3GP"
			(at 1.1811 -2.7051 90)
			(unlocked yes)
			(layer "F.Fab")
			(hide yes)
			(effects
				(font
					(size 1.016 1.016)
					(thickness 0.1524)
				)
			)
		)
		(property "Device Type" "C402H22"
			(at 1.1811 -4.2291 90)
			(unlocked yes)
			(layer "F.Fab")
			(hide yes)
			(effects
				(font
					(size 1.016 1.016)
					(thickness 0.1524)
				)
			)
		)
		(duplicate_pad_numbers_are_jumpers no)
		(fp_rect
			(start -0.4318 0.9525)
			(end 0.4318 -0.9525)
			(stroke
				(width 0)
				(type default)
			)
			(fill no)
			(layer "F.CrtYd")
		)
		(fp_rect
			(start -0.4318 0.9525)
			(end 0.4318 -0.9525)
			(stroke
				(width 0)
				(type default)
			)
			(fill no)
			(layer "F.Fab")
		)
		(pad "1" smd custom
			(at 0 -0.4445 90)
			(size 0.1524 0.1524)
			(layers "F.Cu" "F.Mask" "F.Paste")
			(net "P3V3_DPB")
			(options
				(clearance outline)
				(anchor circle)
			)
			(primitives
				(gr_poly
					(pts
						(arc
							(start 0.3048 -0.2032)
							(mid 0.275042 -0.275042)
							(end 0.2032 -0.3048)
						)
						(arc
							(start -0.2032 -0.3048)
							(mid -0.275042 -0.275042)
							(end -0.3048 -0.2032)
						)
						(arc
							(start -0.3048 0.2032)
							(mid -0.275042 0.275042)
							(end -0.2032 0.3048)
						)
						(arc
							(start 0.2032 0.3048)
							(mid 0.275042 0.275042)
							(end 0.3048 0.2032)
						)
					)
					(width 0)
					(fill yes)
				)
			)
		)
		(pad "2" smd custom
			(at 0 0.4445 90)
			(size 0.1524 0.1524)
			(layers "F.Cu" "F.Mask" "F.Paste")
			(net "GND")
			(options
				(clearance outline)
				(anchor circle)
			)
			(primitives
				(gr_poly
					(pts
						(arc
							(start 0.3048 -0.2032)
							(mid 0.275042 -0.275042)
							(end 0.2032 -0.3048)
						)
						(arc
							(start -0.2032 -0.3048)
							(mid -0.275042 -0.275042)
							(end -0.3048 -0.2032)
						)
						(arc
							(start -0.3048 0.2032)
							(mid -0.275042 0.275042)
							(end -0.2032 0.3048)
						)
						(arc
							(start 0.2032 0.3048)
							(mid 0.275042 0.275042)
							(end 0.3048 0.2032)
						)
					)
					(width 0)
					(fill yes)
				)
			)
		)
	)
	(footprint ""
		(layer "F.Cu")
		(at 65.46088 -95.57258 -90)
		(property "Reference" "C638"
			(at 0 0 270)
			(layer "F.SilkS")
			(hide yes)
			(effects
				(font
					(size 1.27 1.27)
				)
			)
		)
		(property "Value" "SC1U16V3KX-5GP"
			(at 0 -2.8194 270)
			(unlocked yes)
			(layer "F.Fab")
			(hide yes)
			(effects
				(font
					(size 1.016 1.016)
					(thickness 0.1524)
				)
			)
		)
		(property "Device Type" "C603H36"
			(at 0 -4.3434 270)
			(unlocked yes)
			(layer "F.Fab")
			(hide yes)
			(effects
				(font
					(size 1.016 1.016)
					(thickness 0.1524)
				)
			)
		)
		(duplicate_pad_numbers_are_jumpers no)
		(fp_line
			(start 0.508 0)
			(end -0.508 0)
			(stroke
				(width 0.2032)
				(type default)
			)
			(layer "F.SilkS")
		)
		(fp_rect
			(start -0.5842 1.3335)
			(end 0.5842 -1.3335)
			(stroke
				(width 0)
				(type default)
			)
			(fill no)
			(layer "F.CrtYd")
		)
		(fp_rect
			(start -0.5842 1.3335)
			(end 0.5842 -1.3335)
			(stroke
				(width 0)
				(type default)
			)
			(fill no)
			(layer "F.Fab")
		)
		(pad "1" smd custom
			(at 0 -0.762 270)
			(size 0.2159 0.2159)
			(layers "F.Cu" "F.Mask" "F.Paste")
			(net "GND")
			(options
				(clearance outline)
				(anchor circle)
			)
			(primitives
				(gr_poly
					(pts
						(arc
							(start -0.3302 -0.4318)
							(mid -0.402042 -0.402042)
							(end -0.4318 -0.3302)
						)
						(arc
							(start -0.4318 0.3302)
							(mid -0.402042 0.402042)
							(end -0.3302 0.4318)
						)
						(arc
							(start 0.3302 0.4318)
							(mid 0.402042 0.402042)
							(end 0.4318 0.3302)
						)
						(arc
							(start 0.4318 -0.3302)
							(mid 0.402042 -0.402042)
							(end 0.3302 -0.4318)
						)
					)
					(width 0)
					(fill yes)
				)
			)
		)
		(pad "2" smd custom
			(at 0 0.762 270)
			(size 0.2159 0.2159)
			(layers "F.Cu" "F.Mask" "F.Paste")
			(net "P3V3_VREG")
			(options
				(clearance outline)
				(anchor circle)
			)
			(primitives
				(gr_poly
					(pts
						(arc
							(start -0.3302 -0.4318)
							(mid -0.402042 -0.402042)
							(end -0.4318 -0.3302)
						)
						(arc
							(start -0.4318 0.3302)
							(mid -0.402042 0.402042)
							(end -0.3302 0.4318)
						)
						(arc
							(start 0.3302 0.4318)
							(mid 0.402042 0.402042)
							(end 0.4318 0.3302)
						)
						(arc
							(start 0.4318 -0.3302)
							(mid 0.402042 -0.402042)
							(end 0.3302 -0.4318)
						)
					)
					(width 0)
					(fill yes)
				)
			)
		)
	)
	(footprint ""
		(layer "F.Cu")
		(at 181.8386 -124.3076 90)
		(property "Reference" "C596"
			(at 0 0 90)
			(layer "F.SilkS")
			(hide yes)
			(effects
				(font
					(size 1.27 1.27)
				)
			)
		)
		(property "Value" "SCD1U16V2KX-3GP"
			(at 1.1811 -2.7051 90)
			(unlocked yes)
			(layer "F.Fab")
			(hide yes)
			(effects
				(font
					(size 1.016 1.016)
					(thickness 0.1524)
				)
			)
		)
		(property "Device Type" "C402H22"
			(at 1.1811 -4.2291 90)
			(unlocked yes)
			(layer "F.Fab")
			(hide yes)
			(effects
				(font
					(size 1.016 1.016)
					(thickness 0.1524)
				)
			)
		)
		(duplicate_pad_numbers_are_jumpers no)
		(fp_rect
			(start -0.4318 0.9525)
			(end 0.4318 -0.9525)
			(stroke
				(width 0)
				(type default)
			)
			(fill no)
			(layer "F.CrtYd")
		)
		(fp_rect
			(start -0.4318 0.9525)
			(end 0.4318 -0.9525)
			(stroke
				(width 0)
				(type default)
			)
			(fill no)
			(layer "F.Fab")
		)
		(pad "1" smd custom
			(at 0 -0.4445 90)
			(size 0.1524 0.1524)
			(layers "F.Cu" "F.Mask" "F.Paste")
			(net "P1V8_E_OUT")
			(options
				(clearance outline)
				(anchor circle)
			)
			(primitives
				(gr_poly
					(pts
						(arc
							(start 0.3048 -0.2032)
							(mid 0.275042 -0.275042)
							(end 0.2032 -0.3048)
						)
						(arc
							(start -0.2032 -0.3048)
							(mid -0.275042 -0.275042)
							(end -0.3048 -0.2032)
						)
						(arc
							(start -0.3048 0.2032)
							(mid -0.275042 0.275042)
							(end -0.2032 0.3048)
						)
						(arc
							(start 0.2032 0.3048)
							(mid 0.275042 0.275042)
							(end 0.3048 0.2032)
						)
					)
					(width 0)
					(fill yes)
				)
			)
		)
		(pad "2" smd custom
			(at 0 0.4445 90)
			(size 0.1524 0.1524)
			(layers "F.Cu" "F.Mask" "F.Paste")
			(net "GND")
			(options
				(clearance outline)
				(anchor circle)
			)
			(primitives
				(gr_poly
					(pts
						(arc
							(start 0.3048 -0.2032)
							(mid 0.275042 -0.275042)
							(end 0.2032 -0.3048)
						)
						(arc
							(start -0.2032 -0.3048)
							(mid -0.275042 -0.275042)
							(end -0.3048 -0.2032)
						)
						(arc
							(start -0.3048 0.2032)
							(mid -0.275042 0.275042)
							(end -0.2032 0.3048)
						)
						(arc
							(start 0.2032 0.3048)
							(mid 0.275042 0.275042)
							(end 0.3048 0.2032)
						)
					)
					(width 0)
					(fill yes)
				)
			)
		)
	)
	(footprint ""
		(layer "F.Cu")
		(at 139.057634 -78.427834 180)
		(property "Reference" "VIA26"
			(at 0 0 180)
			(layer "F.SilkS")
			(hide yes)
			(effects
				(font
					(size 1.27 1.27)
				)
			)
		)
		(property "Value" "100OHM-8L-1D6MM-L18L16-GP"
			(at -3.7211 -4.5085 180)
			(unlocked yes)
			(layer "F.Fab")
			(hide yes)
			(effects
				(font
					(size 1.016 1.016)
					(thickness 0.1524)
				)
			)
		)
		(property "Device Type" "VIA-PCIE-4P-394076"
			(at -3.7211 -6.0325 180)
			(unlocked yes)
			(layer "F.Fab")
			(hide yes)
			(effects
				(font
					(size 1.016 1.016)
					(thickness 0.1524)
				)
			)
		)
		(duplicate_pad_numbers_are_jumpers no)
		(fp_rect
			(start -1.9685 0.381)
			(end 1.9685 -0.381)
			(stroke
				(width 0)
				(type default)
			)
			(fill no)
			(layer "F.CrtYd")
		)
		(fp_rect
			(start -1.9685 0.381)
			(end 1.9685 -0.381)
			(stroke
				(width 0)
				(type default)
			)
			(fill no)
			(layer "F.Fab")
		)
		(pad "1" thru_hole circle
			(at -1.5875 0 180)
			(size 0.508 0.508)
			(drill 0.254)
			(layers "*.Cu" "*.Mask")
			(remove_unused_layers no)
			(net "GND")
			(clearance 0.127)
			(thermal_gap 0.127)
		)
		(pad "2" thru_hole circle
			(at -0.5715 0 180)
			(size 0.508 0.508)
			(drill 0.254)
			(layers "*.Cu" "*.Mask")
			(remove_unused_layers no)
			(net "PHY_EXP_TO_CONN_9_DP")
			(clearance 0.127)
			(thermal_gap 0.127)
		)
		(pad "3" thru_hole circle
			(at 0.5715 0 180)
			(size 0.508 0.508)
			(drill 0.254)
			(layers "*.Cu" "*.Mask")
			(remove_unused_layers no)
			(net "PHY_EXP_TO_CONN_9_DN")
			(clearance 0.127)
			(thermal_gap 0.127)
		)
		(pad "4" thru_hole circle
			(at 1.5875 0 180)
			(size 0.508 0.508)
			(drill 0.254)
			(layers "*.Cu" "*.Mask")
			(remove_unused_layers no)
			(net "GND")
			(clearance 0.127)
			(thermal_gap 0.127)
		)
	)
)
